#ISCELL
  mstr_misc dns *
  *
#ISCELL
  pure_quanta quanta_title_block_c *
  *
#ISCELL
  standard offpage *
  page183_i1
#ISCELL
  standard offpage *
  page183_i10
#CELL
  pure_quanta q_inductor *
  page183_i101
#ISCELL
  pure_quanta_power vcc_core *
  page183_i104
#CELL
  pure_quanta q_inductor *
  page183_i105
#CELL
  pure_quanta q_cap *
  page183_i107
#CELL
  pure_quanta q_res *
  page183_i110
#CELL
  pure_quanta q_res *
  page183_i111
#CELL
  pure_quanta q_capp *
  page183_i118
#CELL
  pure_quanta q_capp *
  page183_i119
#CELL
  pure_quanta q_capp *
  page183_i120
#CELL
  pure_quanta q_capp *
  page183_i121
#ISCELL
  pure_quanta_power vcc_core *
  page183_i122
#ISCELL
  pure_quanta_power universal_gnd *
  page183_i123
#CELL
  pure_quanta q_cap *
  page183_i124
#CELL
  pure_quanta q_cap *
  page183_i125
#CELL
  pure_quanta q_cap *
  page183_i126
#ISCELL
  pure_quanta_power universal_gnd *
  page183_i127
#ISCELL
  pure_quanta_power universal_gnd *
  page183_i128
#CELL
  pure_quanta q_res *
  page183_i129
#CELL
  pure_quanta q_cap *
  page183_i130
#CELL
  pure_quanta q_cap *
  page183_i132
#ISCELL
  pure_quanta_power universal_gnd *
  page183_i133
#ISCELL
  pure_quanta_power universal_gnd *
  page183_i134
#CELL
  pure_quanta q_res *
  page183_i135
#CELL
  pure_quanta q_cap *
  page183_i136
#CELL
  pure_quanta q_cap *
  page183_i138
#CELL
  pure_quanta q_cap *
  page183_i139
#ISCELL
  pure_quanta_power universal_gnd *
  page183_i140
#CELL
  pure_quanta q_res *
  page183_i141
#CELL
  pure_quanta q_cap *
  page183_i142
#ISCELL
  pure_quanta_power universal_gnd *
  page183_i143
#CELL
  pure_quanta q_res *
  page183_i144
#CELL
  pure_quanta q_cap *
  page183_i145
#ISCELL
  pure_quanta_power vcc_core *
  page183_i146
#ISCELL
  pure_quanta_power vcc_core *
  page183_i147
#ISCELL
  pure_quanta_power vcc_core *
  page183_i148
#CELL
  pure_quanta q_res *
  page183_i149
#CELL
  pure_quanta q_res *
  page183_i15
#ISCELL
  pure_quanta_power vcc_core *
  page183_i150
#CELL
  pure_quanta q_res *
  page183_i151
#CELL
  pure_quanta q_res *
  page183_i152
#CELL
  pure_quanta q_capp *
  page183_i153
#CELL
  pure_quanta q_capp *
  page183_i154
#CELL
  pure_quanta q_res *
  page183_i19
#ISCELL
  pure_quanta_power universal_gnd *
  page183_i2
#CELL
  pure_quanta q_cap *
  page183_i23
#CELL
  pure_quanta q_cap *
  page183_i24
#CELL
  pure_quanta q_cap *
  page183_i25
#CELL
  pure_quanta q_cap *
  page183_i26
#CELL
  pure_quanta q_capp *
  page183_i27
#CELL
  pure_quanta q_cap *
  page183_i29
#ISCELL
  standard offpage *
  page183_i3
#ISCELL
  pure_quanta_power universal_gnd *
  page183_i31
#CELL
  pure_quanta q_inductor *
  page183_i34
#ISCELL
  pure_quanta_power vcc_core *
  page183_i35
#CELL
  pure_quanta q_cap *
  page183_i37
#ISCELL
  pure_quanta_power universal_gnd *
  page183_i38
#CELL
  pure_quanta q_cap *
  page183_i39
#CELL
  pure_quanta q_cap *
  page183_i4
#ISCELL
  pure_quanta_power vcc_core *
  page183_i40
#CELL
  pure_quanta q_cap *
  page183_i43
#CELL
  pure_quanta isl99390frztr5935 *
  page183_i44
#ISCELL
  standard offpage *
  page183_i45
#ISCELL
  pure_quanta_power universal_gnd *
  page183_i46
#ISCELL
  standard offpage *
  page183_i47
#CELL
  pure_quanta q_cap *
  page183_i48
#ISCELL
  pure_quanta_power universal_gnd *
  page183_i49
#ISCELL
  pure_quanta_power universal_gnd *
  page183_i5
#ISCELL
  pure_quanta_power universal_gnd *
  page183_i50
#ISCELL
  standard offpage *
  page183_i51
#CELL
  pure_quanta q_res *
  page183_i52
#ISCELL
  standard offpage *
  page183_i55
#ISCELL
  pure_quanta_power universal_gnd *
  page183_i6
#CELL
  pure_quanta q_res *
  page183_i63
#CELL
  pure_quanta q_cap *
  page183_i66
#CELL
  pure_quanta q_cap *
  page183_i67
#CELL
  pure_quanta q_cap *
  page183_i69
#ISCELL
  standard offpage *
  page183_i7
#CELL
  pure_quanta q_cap *
  page183_i70
#ISCELL
  pure_quanta_power universal_gnd *
  page183_i71
#ISCELL
  pure_quanta_power vcc_core *
  page183_i73
#CELL
  pure_quanta q_cap *
  page183_i79
#ISCELL
  pure_quanta_power universal_gnd *
  page183_i80
#CELL
  pure_quanta q_cap *
  page183_i81
#ISCELL
  pure_quanta_power vcc_core *
  page183_i82
#CELL
  pure_quanta isl99390frztr5935 *
  page183_i84
#ISCELL
  pure_quanta_power universal_gnd *
  page183_i90
#ISCELL
  pure_quanta_power vcc_core *
  page183_i93
#CELL
  pure_quanta q_capp *
  page183_i98
